FILE_TYPE = MACRO_DRAWING;
SET COLOR_WIRE YELLOW;
SET COLOR_PROP ORANGE;
SET COLOR_DOT WHITE;
SET COLOR_ARC YELLOW;
SET COLOR_BODY GREEN;
SET COLOR_NOTE PURPLE;
SET PROP_DISPLAY VALUE;
SET PAGE_NUMBER P254;
FORCEADD OFFPAGE..1
(-8850 5600);
PAINT AQUA (-8850 5600);
FORCEPROP 2 LAST $XR0 254 
J 0
(-9102 5600);
DISPLAY 0.638298 (-9102 5600);
PAINT MONO (-9102 5600);
FORCEPROP 2 LAST CDS_LIB standard
J 0
(-8850 5600);
DISPLAY INVISIBLE (-8850 5600);
FORCEPROP 1 LAST OFFPAGE TRUE
J 0
(-8525 5475);
DISPLAY 0.872340 (-8525 5475);
PAINT AQUA (-8525 5475);
DISPLAY INVISIBLE (-8525 5475);
FORCEPROP 1 LAST COMMENT_BODY TRUE
J 0
(-8725 5500);
DISPLAY 0.872340 (-8725 5500);
PAINT GREEN (-8725 5500);
DISPLAY INVISIBLE (-8725 5500);
FORCEPROP 2 LAST PATH I1
J 0
(-9100 5650);
DISPLAY 0.680851 (-9100 5650);
DISPLAY INVISIBLE (-9100 5650);
FORCEADD UNIVERSAL_POWER..1
(-500 1200);
FORCEPROP 3 LASTPIN (-500 1150) SIG_NAME P3V3\g
J 0
(-490 1160);
DISPLAY 0.659574 (-490 1160);
PAINT MONO (-490 1160);
DISPLAY INVISIBLE (-490 1160);
FORCEPROP 1 LAST HDL_POWER P3V3
J 1
(-500 1250);
DISPLAY 0.723404 (-500 1250);
PAINT GREEN (-500 1250);
FORCEPROP 2 LAST CDS_LIB pure_quanta_power
J 0
(-500 1200);
DISPLAY INVISIBLE (-500 1200);
FORCEPROP 1 LAST PATH I10
J 0
(-450 1225);
DISPLAY 0.872340 (-450 1225);
PAINT AQUA (-450 1225);
DISPLAY INVISIBLE (-450 1225);
FORCEADD UNIVERSAL_POWER..1
(-550 2450);
FORCEPROP 3 LASTPIN (-550 2400) SIG_NAME P5V\g
J 0
(-540 2410);
DISPLAY 0.659574 (-540 2410);
PAINT MONO (-540 2410);
DISPLAY INVISIBLE (-540 2410);
FORCEPROP 1 LAST HDL_POWER P5V
J 1
(-550 2500);
DISPLAY 0.723404 (-550 2500);
PAINT GREEN (-550 2500);
FORCEPROP 2 LAST CDS_LIB pure_quanta_power
J 0
(-550 2450);
DISPLAY INVISIBLE (-550 2450);
FORCEPROP 1 LAST PATH I11
J 0
(-500 2475);
DISPLAY 0.872340 (-500 2475);
PAINT AQUA (-500 2475);
DISPLAY INVISIBLE (-500 2475);
FORCEADD Q_LED..1
R 2
(-6675 5925);
FORCEPROP 1 LAST LOCATION D96
J 0
(-6775 5850);
DISPLAY 0.723404 (-6775 5850);
PAINT GREEN (-6775 5850);
FORCEPROP 0 LAST $SEC 1
J 0
(-6775 5900);
DISPLAY INVISIBLE (-6775 5900);
FORCEPROP 0 LAST CDS_SEC 1
J 0
(-6775 5900);
DISPLAY INVISIBLE (-6775 5900);
FORCEPROP 0 LASTPIN (-6525 5925) $PN A
J 0
(-6515 5935);
DISPLAY 0.808511 (-6515 5935);
FORCEPROP 0 LASTPIN (-6825 5925) $PN C
J 2
(-6835 5935);
DISPLAY 0.808511 (-6835 5935);
FORCEPROP 0 LAST PACK_TYPE SMLF
J 0
(-6775 5750);
DISPLAY 0.638298 (-6775 5750);
FORCEPROP 2 LAST COLOR LED_BLUE
J 0
(-6775 5800);
DISPLAY 0.638298 (-6775 5800);
FORCEPROP 1 LAST MATERIAL IC
J 0
(-6650 5750);
DISPLAY 0.723404 (-6650 5750);
PAINT GREEN (-6650 5750);
FORCEPROP 2 LAST MANUF_PN LTST-C281TBKT-5A
J 0
(-6775 5650);
DISPLAY 0.638298 (-6775 5650);
FORCEPROP 2 LAST CDS_LIB pure_quanta
J 0
(-6675 5925);
DISPLAY INVISIBLE (-6675 5925);
FORCEPROP 1 LAST NEEDS_NO_SIZE TRUE
J 2
(-6653 5947);
DISPLAY 0.468085 (-6653 5947);
PAINT GREEN (-6653 5947);
DISPLAY INVISIBLE (-6653 5947);
FORCEPROP 1 LAST PATH I14
J 2
(-6800 6005);
DISPLAY 0.723404 (-6800 6005);
PAINT GREEN (-6800 6005);
DISPLAY INVISIBLE (-6800 6005);
FORCEPROP 1 LAST PART_NUMBER BEBL0172Z00
J 0
(-6775 5700);
DISPLAY 0.574468 (-6775 5700);
PAINT GREEN (-6775 5700);
DISPLAY INVISIBLE (-6775 5700);
FORCEADD Q_RES..1
(-5375 5925);
FORCEPROP 1 LAST LOCATION R3075
J 0
(-5425 5975);
DISPLAY 0.978723 (-5425 5975);
FORCEPROP 0 LAST $SEC 1
J 0
(-5425 6025);
DISPLAY 0.680851 (-5425 6025);
PAINT MONO (-5425 6025);
DISPLAY INVISIBLE (-5425 6025);
FORCEPROP 0 LAST CDS_SEC 1
J 0
(-5425 6025);
DISPLAY 1.021277 (-5425 6025);
DISPLAY INVISIBLE (-5425 6025);
FORCEPROP 1 LASTPIN (-5475 5925) $PN 1
J 0
(-5463 5937);
DISPLAY 0.787234 (-5463 5937);
PAINT MONO (-5463 5937);
FORCEPROP 1 LASTPIN (-5275 5925) $PN 2
J 0
(-5313 5937);
DISPLAY 0.787234 (-5313 5937);
PAINT MONO (-5313 5937);
FORCEPROP 1 LAST TOLERANCE 1%
J 0
(-5150 5925);
DISPLAY 0.638298 (-5150 5925);
FORCEPROP 1 LAST VALUE 130
J 2
(-5175 5925);
DISPLAY 0.638298 (-5175 5925);
FORCEPROP 1 LAST MATERIAL CHIP
J 0
(-5525 5875);
DISPLAY 0.638298 (-5525 5875);
FORCEPROP 1 LAST WATTAGE 1/16W
J 2
(-5225 5875);
DISPLAY 0.638298 (-5225 5875);
FORCEPROP 1 LAST PACK_TYPE 0402LF
J 0
(-5075 5925);
DISPLAY 0.638298 (-5075 5925);
FORCEPROP 2 LAST CDS_LIB pure_quanta
J 0
(-5375 5925);
DISPLAY INVISIBLE (-5375 5925);
FORCEPROP 1 LAST PATH I15
J 0
(-5425 6075);
DISPLAY 0.978723 (-5425 6075);
PAINT WHITE (-5425 6075);
DISPLAY INVISIBLE (-5425 6075);
FORCEPROP 1 LAST PART_NUMBER CS11302FB03
J 0
(-5600 6025);
DISPLAY 0.638298 (-5600 6025);
DISPLAY INVISIBLE (-5600 6025);
FORCEADD UNIVERSAL_POWER..1
(-4725 6075);
FORCEPROP 3 LASTPIN (-4725 6025) SIG_NAME P3V3_AUX\g
J 0
(-4715 6035);
DISPLAY 0.659574 (-4715 6035);
PAINT MONO (-4715 6035);
DISPLAY INVISIBLE (-4715 6035);
FORCEPROP 1 LAST HDL_POWER P3V3_AUX
J 1
(-4725 6125);
DISPLAY 0.723404 (-4725 6125);
PAINT GREEN (-4725 6125);
FORCEPROP 2 LAST CDS_LIB pure_quanta_power
J 0
(-4725 6075);
DISPLAY INVISIBLE (-4725 6075);
FORCEPROP 1 LAST PATH I16
J 0
(-4675 6100);
DISPLAY 0.872340 (-4675 6100);
PAINT AQUA (-4675 6100);
DISPLAY INVISIBLE (-4675 6100);
FORCEADD Q_LED..1
R 2
(-2050 2200);
FORCEPROP 1 LAST LOCATION D98
J 0
(-2150 2125);
DISPLAY 0.723404 (-2150 2125);
PAINT GREEN (-2150 2125);
FORCEPROP 0 LAST $SEC 1
J 0
(-2150 2175);
DISPLAY INVISIBLE (-2150 2175);
FORCEPROP 0 LAST CDS_SEC 1
J 0
(-2150 2175);
DISPLAY INVISIBLE (-2150 2175);
FORCEPROP 0 LASTPIN (-1900 2200) $PN A
J 0
(-1890 2210);
DISPLAY 0.808511 (-1890 2210);
FORCEPROP 0 LASTPIN (-2200 2200) $PN C
J 2
(-2210 2210);
DISPLAY 0.808511 (-2210 2210);
FORCEPROP 2 LAST MANUF_PN LTST-C281TBKT-5A
J 0
(-2150 1925);
DISPLAY 0.638298 (-2150 1925);
FORCEPROP 1 LAST MATERIAL IC
J 0
(-2025 2025);
DISPLAY 0.723404 (-2025 2025);
PAINT GREEN (-2025 2025);
FORCEPROP 0 LAST PACK_TYPE SMLF
J 0
(-2150 2025);
DISPLAY 0.638298 (-2150 2025);
FORCEPROP 2 LAST COLOR LED_BLUE
J 0
(-2150 2075);
DISPLAY 0.638298 (-2150 2075);
FORCEPROP 2 LAST CDS_LIB pure_quanta
J 0
(-2050 2200);
DISPLAY INVISIBLE (-2050 2200);
FORCEPROP 1 LAST NEEDS_NO_SIZE TRUE
J 2
(-2028 2222);
DISPLAY 0.468085 (-2028 2222);
PAINT GREEN (-2028 2222);
DISPLAY INVISIBLE (-2028 2222);
FORCEPROP 1 LAST PATH I17
J 2
(-2175 2280);
DISPLAY 0.723404 (-2175 2280);
PAINT GREEN (-2175 2280);
DISPLAY INVISIBLE (-2175 2280);
FORCEPROP 1 LAST PART_NUMBER BEBL0172Z00
J 0
(-2150 1975);
DISPLAY 0.574468 (-2150 1975);
PAINT GREEN (-2150 1975);
DISPLAY INVISIBLE (-2150 1975);
FORCEADD MOSFET_NCH_DUAL..2
(-7750 5650);
FORCEPROP 1 LAST LOCATION Q78
J 0
(-7599 5626);
DISPLAY 0.723404 (-7599 5626);
PAINT AQUA (-7599 5626);
FORCEPROP 2 LAST SEC 2
J 0
(-7575 5775);
DISPLAY 0.680851 (-7575 5775);
PAINT MONO (-7575 5775);
DISPLAY INVISIBLE (-7575 5775);
FORCEPROP 2 LASTPIN (-7700 5850) $PN 3
R 1
J 0
(-7710 5860);
DISPLAY 0.723404 (-7710 5860);
PAINT MONO (-7710 5860);
FORCEPROP 2 LASTPIN (-7950 5600) $PN 5
J 2
(-7960 5610);
DISPLAY 0.723404 (-7960 5610);
PAINT MONO (-7960 5610);
FORCEPROP 2 LASTPIN (-7700 5450) $PN 4
R 1
J 2
(-7710 5440);
DISPLAY 0.723404 (-7710 5440);
PAINT MONO (-7710 5440);
FORCEPROP 2 LAST VALUE PJT138K
J 0
(-7575 5675);
DISPLAY 0.723404 (-7575 5675);
PAINT SKYBLUE (-7575 5675);
FORCEPROP 1 LAST MATERIAL IC
J 0
(-7599 5501);
DISPLAY 0.723404 (-7599 5501);
PAINT SKYBLUE (-7599 5501);
FORCEPROP 2 LAST PART_TYPE SMLF
J 0
(-7575 5725);
DISPLAY 1.021277 (-7575 5725);
FORCEPROP 2 LAST SEC_TYPE 
J 0
(-7575 5775);
DISPLAY 1.021277 (-7575 5775);
DISPLAY INVISIBLE (-7575 5775);
FORCEPROP 2 LAST CDS_LIB pure_quanta
J 0
(-7750 5650);
DISPLAY INVISIBLE (-7750 5650);
FORCEPROP 1 LAST NEEDS_NO_SIZE TRUE
J 0
(-7600 5541);
DISPLAY 0.468085 (-7600 5541);
PAINT GREEN (-7600 5541);
DISPLAY INVISIBLE (-7600 5541);
FORCEPROP 1 LAST CDS_LMAN_SYM_OUTLINE -150,150,150,-150
J 0
(-7750 5650);
DISPLAY 0.468085 (-7750 5650);
PAINT GREEN (-7750 5650);
DISPLAY INVISIBLE (-7750 5650);
FORCEPROP 1 LAST PATH I18
J 0
(-7600 5500);
DISPLAY 0.723404 (-7600 5500);
PAINT GREEN (-7600 5500);
DISPLAY INVISIBLE (-7600 5500);
FORCEPROP 1 LAST PART_NUMBER BAM138K0003
J 0
(-7599 5556);
DISPLAY 0.723404 (-7599 5556);
PAINT BLUE (-7599 5556);
DISPLAY INVISIBLE (-7599 5556);
FORCEADD OFFPAGE..1
(-8775 4225);
PAINT AQUA (-8775 4225);
FORCEPROP 2 LAST $XR3 271 
J 0
(-9357 4225);
DISPLAY 0.638298 (-9357 4225);
PAINT MONO (-9357 4225);
FORCEPROP 2 LAST $XR2 148 
J 0
(-9237 4225);
DISPLAY 0.638298 (-9237 4225);
PAINT MONO (-9237 4225);
FORCEPROP 2 LAST $XR1 81 
J 0
(-9117 4225);
DISPLAY 0.638298 (-9117 4225);
PAINT MONO (-9117 4225);
FORCEPROP 2 LAST $XR0 270 
J 0
(-9027 4225);
DISPLAY 0.638298 (-9027 4225);
PAINT MONO (-9027 4225);
FORCEPROP 2 LAST CDS_LIB standard
J 0
(-8775 4225);
DISPLAY INVISIBLE (-8775 4225);
FORCEPROP 1 LAST OFFPAGE TRUE
J 0
(-8450 4100);
DISPLAY 0.872340 (-8450 4100);
PAINT AQUA (-8450 4100);
DISPLAY INVISIBLE (-8450 4100);
FORCEPROP 1 LAST COMMENT_BODY TRUE
J 0
(-8650 4125);
DISPLAY 0.872340 (-8650 4125);
PAINT GREEN (-8650 4125);
DISPLAY INVISIBLE (-8650 4125);
FORCEPROP 2 LAST PATH I19
J 0
(-9025 4300);
DISPLAY 0.680851 (-9025 4300);
DISPLAY INVISIBLE (-9025 4300);
FORCEADD UNIVERSAL_GND..1
(-2725 725);
FORCEPROP 3 LASTPIN (-2725 775) SIG_NAME GND\g
J 0
(-2715 785);
DISPLAY 0.659574 (-2715 785);
PAINT MONO (-2715 785);
DISPLAY INVISIBLE (-2715 785);
FORCEPROP 2 LAST CDS_LIB pure_quanta_power
J 0
(-2725 725);
DISPLAY INVISIBLE (-2725 725);
FORCEPROP 1 LAST HDL_POWER GND
J 1
(-2700 650);
DISPLAY 0.872340 (-2700 650);
PAINT GREEN (-2700 650);
DISPLAY INVISIBLE (-2700 650);
FORCEPROP 1 LAST PATH I2
J 0
(-2650 725);
DISPLAY 0.872340 (-2650 725);
PAINT AQUA (-2650 725);
DISPLAY INVISIBLE (-2650 725);
FORCEADD UNIVERSAL_GND..1
(-7625 3925);
FORCEPROP 3 LASTPIN (-7625 3975) SIG_NAME GND\g
J 0
(-7615 3985);
DISPLAY 0.659574 (-7615 3985);
PAINT MONO (-7615 3985);
DISPLAY INVISIBLE (-7615 3985);
FORCEPROP 2 LAST CDS_LIB pure_quanta_power
J 0
(-7625 3925);
DISPLAY INVISIBLE (-7625 3925);
FORCEPROP 1 LAST HDL_POWER GND
J 1
(-7600 3850);
DISPLAY 0.872340 (-7600 3850);
PAINT GREEN (-7600 3850);
DISPLAY INVISIBLE (-7600 3850);
FORCEPROP 1 LAST PATH I20
J 0
(-7550 3925);
DISPLAY 0.872340 (-7550 3925);
PAINT AQUA (-7550 3925);
DISPLAY INVISIBLE (-7550 3925);
FORCEADD Q_RES..1
(-5250 4550);
FORCEPROP 1 LAST LOCATION R3071
J 0
(-5300 4600);
DISPLAY 0.978723 (-5300 4600);
FORCEPROP 0 LAST $SEC 1
J 0
(-5300 4650);
DISPLAY 0.680851 (-5300 4650);
PAINT MONO (-5300 4650);
DISPLAY INVISIBLE (-5300 4650);
FORCEPROP 0 LAST CDS_SEC 1
J 0
(-5300 4650);
DISPLAY 1.021277 (-5300 4650);
DISPLAY INVISIBLE (-5300 4650);
FORCEPROP 1 LASTPIN (-5350 4550) $PN 1
J 0
(-5338 4562);
DISPLAY 0.787234 (-5338 4562);
PAINT MONO (-5338 4562);
FORCEPROP 1 LASTPIN (-5150 4550) $PN 2
J 0
(-5188 4562);
DISPLAY 0.787234 (-5188 4562);
PAINT MONO (-5188 4562);
FORCEPROP 1 LAST PACK_TYPE 0402LF
J 0
(-4950 4550);
DISPLAY 0.638298 (-4950 4550);
FORCEPROP 1 LAST TOLERANCE 1%
J 0
(-5025 4550);
DISPLAY 0.638298 (-5025 4550);
FORCEPROP 1 LAST VALUE 130
J 2
(-5050 4550);
DISPLAY 0.638298 (-5050 4550);
FORCEPROP 1 LAST MATERIAL CHIP
J 0
(-5400 4500);
DISPLAY 0.638298 (-5400 4500);
FORCEPROP 1 LAST WATTAGE 1/16W
J 2
(-5100 4500);
DISPLAY 0.638298 (-5100 4500);
FORCEPROP 2 LAST CDS_LIB pure_quanta
J 0
(-5250 4550);
DISPLAY INVISIBLE (-5250 4550);
FORCEPROP 1 LAST PATH I21
J 0
(-5300 4700);
DISPLAY 0.978723 (-5300 4700);
PAINT WHITE (-5300 4700);
DISPLAY INVISIBLE (-5300 4700);
FORCEPROP 1 LAST PART_NUMBER CS11302FB03
J 0
(-5475 4650);
DISPLAY 0.638298 (-5475 4650);
DISPLAY INVISIBLE (-5475 4650);
FORCEADD UNIVERSAL_POWER..1
(-4600 4700);
FORCEPROP 3 LASTPIN (-4600 4650) SIG_NAME P3V3_AUX\g
J 0
(-4590 4660);
DISPLAY 0.659574 (-4590 4660);
PAINT MONO (-4590 4660);
DISPLAY INVISIBLE (-4590 4660);
FORCEPROP 1 LAST HDL_POWER P3V3_AUX
J 1
(-4600 4750);
DISPLAY 0.723404 (-4600 4750);
PAINT GREEN (-4600 4750);
FORCEPROP 2 LAST CDS_LIB pure_quanta_power
J 0
(-4600 4700);
DISPLAY INVISIBLE (-4600 4700);
FORCEPROP 1 LAST PATH I22
J 0
(-4550 4725);
DISPLAY 0.872340 (-4550 4725);
PAINT AQUA (-4550 4725);
DISPLAY INVISIBLE (-4550 4725);
FORCEADD Q_LED..1
R 2
(-6600 4550);
FORCEPROP 1 LAST LOCATION D91
J 0
(-6700 4475);
DISPLAY 0.723404 (-6700 4475);
PAINT GREEN (-6700 4475);
FORCEPROP 0 LAST $SEC 1
J 0
(-6700 4525);
DISPLAY INVISIBLE (-6700 4525);
FORCEPROP 0 LAST CDS_SEC 1
J 0
(-6700 4525);
DISPLAY INVISIBLE (-6700 4525);
FORCEPROP 0 LASTPIN (-6450 4550) $PN A
J 0
(-6440 4560);
DISPLAY 0.808511 (-6440 4560);
FORCEPROP 0 LASTPIN (-6750 4550) $PN C
J 2
(-6760 4560);
DISPLAY 0.808511 (-6760 4560);
FORCEPROP 0 LAST PACK_TYPE SMLF
J 0
(-6700 4375);
DISPLAY 0.638298 (-6700 4375);
FORCEPROP 1 LAST MATERIAL IC
J 0
(-6575 4375);
DISPLAY 0.723404 (-6575 4375);
PAINT GREEN (-6575 4375);
FORCEPROP 2 LAST MANUF_PN LTST-C281TBKT-5A
J 0
(-6700 4275);
DISPLAY 0.638298 (-6700 4275);
FORCEPROP 2 LAST COLOR LED_BLUE
J 0
(-6700 4425);
DISPLAY 0.638298 (-6700 4425);
FORCEPROP 2 LAST CDS_LIB pure_quanta
J 0
(-6600 4550);
DISPLAY INVISIBLE (-6600 4550);
FORCEPROP 1 LAST NEEDS_NO_SIZE TRUE
J 2
(-6578 4572);
DISPLAY 0.468085 (-6578 4572);
PAINT GREEN (-6578 4572);
DISPLAY INVISIBLE (-6578 4572);
FORCEPROP 1 LAST PATH I23
J 2
(-6725 4630);
DISPLAY 0.723404 (-6725 4630);
PAINT GREEN (-6725 4630);
DISPLAY INVISIBLE (-6725 4630);
FORCEPROP 1 LAST PART_NUMBER BEBL0172Z00
J 0
(-6700 4325);
DISPLAY 0.574468 (-6700 4325);
PAINT GREEN (-6700 4325);
DISPLAY INVISIBLE (-6700 4325);
FORCEADD MOSFET_NCH_DUAL..1
(-7675 4275);
FORCEPROP 1 LAST LOCATION Q78
J 0
(-7524 4249);
DISPLAY 0.723404 (-7524 4249);
PAINT GREEN (-7524 4249);
FORCEPROP 0 LAST $SEC 1
J 0
(-7500 4400);
DISPLAY INVISIBLE (-7500 4400);
FORCEPROP 0 LAST CDS_SEC 1
J 0
(-7500 4400);
DISPLAY INVISIBLE (-7500 4400);
FORCEPROP 0 LASTPIN (-7625 4475) $PN 6
R 1
J 0
(-7635 4485);
DISPLAY 0.808511 (-7635 4485);
FORCEPROP 0 LASTPIN (-7875 4225) $PN 2
J 2
(-7885 4235);
DISPLAY 0.808511 (-7885 4235);
FORCEPROP 0 LASTPIN (-7625 4075) $PN 1
R 1
J 2
(-7635 4065);
DISPLAY 0.808511 (-7635 4065);
FORCEPROP 1 LAST MATERIAL IC
J 0
(-7524 4124);
DISPLAY 0.723404 (-7524 4124);
PAINT GREEN (-7524 4124);
FORCEPROP 2 LAST VALUE PJT138K
J 0
(-7500 4300);
DISPLAY 1.021277 (-7500 4300);
FORCEPROP 2 LAST PART_TYPE SMLF
J 0
(-7500 4350);
DISPLAY 1.021277 (-7500 4350);
FORCEPROP 1 LAST NEEDS_NO_SIZE TRUE
J 0
(-7675 4274);
DISPLAY 0.468085 (-7675 4274);
PAINT GREEN (-7675 4274);
DISPLAY INVISIBLE (-7675 4274);
FORCEPROP 1 LAST CDS_LMAN_SYM_OUTLINE -150,150,150,-150
J 0
(-7675 4275);
DISPLAY 0.468085 (-7675 4275);
PAINT GREEN (-7675 4275);
DISPLAY INVISIBLE (-7675 4275);
FORCEPROP 2 LAST CDS_LIB pure_quanta
J 0
(-7675 4275);
DISPLAY INVISIBLE (-7675 4275);
FORCEPROP 1 LAST PATH I24
J 0
(-7675 4275);
DISPLAY 0.723404 (-7675 4275);
PAINT GREEN (-7675 4275);
DISPLAY INVISIBLE (-7675 4275);
FORCEPROP 1 LAST PART_NUMBER BAM138K0003
J 0
(-7524 4189);
DISPLAY 0.723404 (-7524 4189);
PAINT GREEN (-7524 4189);
DISPLAY INVISIBLE (-7524 4189);
FORCEADD Q_LED..1
R 2
(-2125 975);
FORCEPROP 1 LAST LOCATION D99
J 0
(-2225 900);
DISPLAY 0.723404 (-2225 900);
PAINT GREEN (-2225 900);
FORCEPROP 0 LAST $SEC 1
J 0
(-2225 950);
DISPLAY INVISIBLE (-2225 950);
FORCEPROP 0 LAST CDS_SEC 1
J 0
(-2225 950);
DISPLAY INVISIBLE (-2225 950);
FORCEPROP 0 LASTPIN (-1975 975) $PN A
J 0
(-1965 985);
DISPLAY 0.808511 (-1965 985);
FORCEPROP 0 LASTPIN (-2275 975) $PN C
J 2
(-2285 985);
DISPLAY 0.808511 (-2285 985);
FORCEPROP 2 LAST MANUF_PN LTST-C281TBKT-5A
J 0
(-2225 700);
DISPLAY 0.638298 (-2225 700);
FORCEPROP 1 LAST MATERIAL IC
J 0
(-2100 800);
DISPLAY 0.723404 (-2100 800);
PAINT GREEN (-2100 800);
FORCEPROP 0 LAST PACK_TYPE SMLF
J 0
(-2225 800);
DISPLAY 0.638298 (-2225 800);
FORCEPROP 2 LAST COLOR LED_BLUE
J 0
(-2225 850);
DISPLAY 0.638298 (-2225 850);
FORCEPROP 1 LAST NEEDS_NO_SIZE TRUE
J 2
(-2103 997);
DISPLAY 0.468085 (-2103 997);
PAINT GREEN (-2103 997);
DISPLAY INVISIBLE (-2103 997);
FORCEPROP 2 LAST CDS_LIB pure_quanta
J 0
(-2125 975);
DISPLAY INVISIBLE (-2125 975);
FORCEPROP 1 LAST PATH I3
J 2
(-2250 1055);
DISPLAY 0.723404 (-2250 1055);
PAINT GREEN (-2250 1055);
DISPLAY INVISIBLE (-2250 1055);
FORCEPROP 1 LAST PART_NUMBER BEBL0172Z00
J 0
(-2225 750);
DISPLAY 0.574468 (-2225 750);
PAINT GREEN (-2225 750);
DISPLAY INVISIBLE (-2225 750);
FORCEADD UNIVERSAL_POWER..1
(-4725 1675);
FORCEPROP 3 LASTPIN (-4725 1625) SIG_NAME P3V3_AUX\g
J 0
(-4715 1635);
DISPLAY 0.659574 (-4715 1635);
PAINT MONO (-4715 1635);
DISPLAY INVISIBLE (-4715 1635);
FORCEPROP 1 LAST HDL_POWER P3V3_AUX
J 1
(-4725 1725);
DISPLAY 0.723404 (-4725 1725);
PAINT GREEN (-4725 1725);
FORCEPROP 2 LAST CDS_LIB pure_quanta_power
J 0
(-4725 1675);
DISPLAY INVISIBLE (-4725 1675);
FORCEPROP 1 LAST PATH I31
J 0
(-4675 1700);
DISPLAY 0.872340 (-4675 1700);
PAINT AQUA (-4675 1700);
DISPLAY INVISIBLE (-4675 1700);
FORCEADD Q_RES..1
(-5375 1475);
FORCEPROP 1 LAST LOCATION R3069
J 0
(-5425 1525);
DISPLAY 0.978723 (-5425 1525);
FORCEPROP 0 LAST $SEC 1
J 0
(-5425 1575);
DISPLAY 0.680851 (-5425 1575);
PAINT MONO (-5425 1575);
DISPLAY INVISIBLE (-5425 1575);
FORCEPROP 0 LAST CDS_SEC 1
J 0
(-5425 1575);
DISPLAY 1.021277 (-5425 1575);
DISPLAY INVISIBLE (-5425 1575);
FORCEPROP 1 LASTPIN (-5475 1475) $PN 1
J 0
(-5463 1487);
DISPLAY 0.787234 (-5463 1487);
PAINT MONO (-5463 1487);
FORCEPROP 1 LASTPIN (-5275 1475) $PN 2
J 0
(-5313 1487);
DISPLAY 0.787234 (-5313 1487);
PAINT MONO (-5313 1487);
FORCEPROP 1 LAST TOLERANCE 1%
J 0
(-5150 1475);
DISPLAY 0.638298 (-5150 1475);
FORCEPROP 1 LAST PACK_TYPE 0402LF
J 0
(-5075 1475);
DISPLAY 0.638298 (-5075 1475);
FORCEPROP 1 LAST MATERIAL CHIP
J 0
(-5525 1425);
DISPLAY 0.638298 (-5525 1425);
FORCEPROP 1 LAST WATTAGE 1/16W
J 2
(-5225 1425);
DISPLAY 0.638298 (-5225 1425);
FORCEPROP 1 LAST VALUE 130
J 2
(-5175 1475);
DISPLAY 0.638298 (-5175 1475);
FORCEPROP 2 LAST CDS_LIB pure_quanta
J 0
(-5375 1475);
DISPLAY INVISIBLE (-5375 1475);
FORCEPROP 1 LAST PATH I32
J 0
(-5425 1625);
DISPLAY 0.978723 (-5425 1625);
PAINT WHITE (-5425 1625);
DISPLAY INVISIBLE (-5425 1625);
FORCEPROP 1 LAST PART_NUMBER CS11302FB03
J 0
(-5600 1575);
DISPLAY 0.638298 (-5600 1575);
DISPLAY INVISIBLE (-5600 1575);
FORCEADD Q_LED..1
R 2
(-6675 1475);
FORCEPROP 1 LAST LOCATION D88
J 0
(-6775 1375);
DISPLAY 0.723404 (-6775 1375);
PAINT GREEN (-6775 1375);
FORCEPROP 0 LAST $SEC 1
J 0
(-6775 1450);
DISPLAY INVISIBLE (-6775 1450);
FORCEPROP 0 LAST CDS_SEC 1
J 0
(-6775 1450);
DISPLAY INVISIBLE (-6775 1450);
FORCEPROP 0 LASTPIN (-6525 1475) $PN A
J 0
(-6515 1485);
DISPLAY 0.808511 (-6515 1485);
FORCEPROP 0 LASTPIN (-6825 1475) $PN C
J 2
(-6835 1485);
DISPLAY 0.808511 (-6835 1485);
FORCEPROP 0 LAST PACK_TYPE SMLF
J 0
(-6775 1300);
DISPLAY 0.638298 (-6775 1300);
FORCEPROP 1 LAST MATERIAL IC
J 0
(-6650 1300);
DISPLAY 0.723404 (-6650 1300);
PAINT GREEN (-6650 1300);
FORCEPROP 2 LAST MANUF_PN LTST-C281TBKT-5A
J 0
(-6775 1200);
DISPLAY 0.638298 (-6775 1200);
FORCEPROP 2 LAST COLOR LED_BLUE
J 0
(-6775 1350);
DISPLAY 0.638298 (-6775 1350);
FORCEPROP 2 LAST CDS_LIB pure_quanta
J 0
(-6675 1475);
DISPLAY INVISIBLE (-6675 1475);
FORCEPROP 1 LAST NEEDS_NO_SIZE TRUE
J 2
(-6653 1497);
DISPLAY 0.468085 (-6653 1497);
PAINT GREEN (-6653 1497);
DISPLAY INVISIBLE (-6653 1497);
FORCEPROP 1 LAST PATH I33
J 2
(-6800 1555);
DISPLAY 0.723404 (-6800 1555);
PAINT GREEN (-6800 1555);
DISPLAY INVISIBLE (-6800 1555);
FORCEPROP 1 LAST PART_NUMBER BEBL0172Z00
J 0
(-6775 1250);
DISPLAY 0.574468 (-6775 1250);
PAINT GREEN (-6775 1250);
DISPLAY INVISIBLE (-6775 1250);
FORCEADD UNIVERSAL_GND..1
(-7700 850);
FORCEPROP 3 LASTPIN (-7700 900) SIG_NAME GND\g
J 0
(-7690 910);
DISPLAY 0.659574 (-7690 910);
PAINT MONO (-7690 910);
DISPLAY INVISIBLE (-7690 910);
FORCEPROP 2 LAST CDS_LIB pure_quanta_power
J 0
(-7700 850);
DISPLAY INVISIBLE (-7700 850);
FORCEPROP 1 LAST HDL_POWER GND
J 1
(-7675 775);
DISPLAY 0.872340 (-7675 775);
PAINT GREEN (-7675 775);
DISPLAY INVISIBLE (-7675 775);
FORCEPROP 1 LAST PATH I34
J 0
(-7625 850);
DISPLAY 0.872340 (-7625 850);
PAINT AQUA (-7625 850);
DISPLAY INVISIBLE (-7625 850);
FORCEADD MOSFET_NCH_DUAL..2
(-7750 1200);
FORCEPROP 1 LAST LOCATION Q87
J 0
(-7599 1176);
DISPLAY 0.723404 (-7599 1176);
PAINT AQUA (-7599 1176);
FORCEPROP 2 LAST SEC 2
J 0
(-7575 1325);
DISPLAY 0.680851 (-7575 1325);
PAINT MONO (-7575 1325);
DISPLAY INVISIBLE (-7575 1325);
FORCEPROP 2 LASTPIN (-7700 1400) $PN 3
R 1
J 0
(-7710 1410);
DISPLAY 0.723404 (-7710 1410);
PAINT MONO (-7710 1410);
FORCEPROP 2 LASTPIN (-7950 1150) $PN 5
J 2
(-7960 1160);
DISPLAY 0.723404 (-7960 1160);
PAINT MONO (-7960 1160);
FORCEPROP 2 LASTPIN (-7700 1000) $PN 4
R 1
J 2
(-7710 990);
DISPLAY 0.723404 (-7710 990);
PAINT MONO (-7710 990);
FORCEPROP 2 LAST VALUE PJT138K
J 0
(-7575 1225);
DISPLAY 0.723404 (-7575 1225);
PAINT SKYBLUE (-7575 1225);
FORCEPROP 1 LAST MATERIAL IC
J 0
(-7599 1051);
DISPLAY 0.723404 (-7599 1051);
PAINT SKYBLUE (-7599 1051);
FORCEPROP 2 LAST PART_TYPE SMLF
J 0
(-7575 1275);
DISPLAY 1.021277 (-7575 1275);
FORCEPROP 1 LAST CDS_LMAN_SYM_OUTLINE -150,150,150,-150
J 0
(-7750 1200);
DISPLAY 0.468085 (-7750 1200);
PAINT GREEN (-7750 1200);
DISPLAY INVISIBLE (-7750 1200);
FORCEPROP 2 LAST CDS_LIB pure_quanta
J 0
(-7750 1200);
DISPLAY INVISIBLE (-7750 1200);
FORCEPROP 2 LAST SEC_TYPE 
J 0
(-7575 1325);
DISPLAY 1.021277 (-7575 1325);
DISPLAY INVISIBLE (-7575 1325);
FORCEPROP 1 LAST NEEDS_NO_SIZE TRUE
J 0
(-7600 1091);
DISPLAY 0.468085 (-7600 1091);
PAINT GREEN (-7600 1091);
DISPLAY INVISIBLE (-7600 1091);
FORCEPROP 1 LAST PATH I35
J 0
(-7600 1050);
DISPLAY 0.723404 (-7600 1050);
PAINT GREEN (-7600 1050);
DISPLAY INVISIBLE (-7600 1050);
FORCEPROP 1 LAST PART_NUMBER BAM138K0003
J 0
(-7599 1106);
DISPLAY 0.723404 (-7599 1106);
PAINT BLUE (-7599 1106);
DISPLAY INVISIBLE (-7599 1106);
FORCEADD OFFPAGE..1
(-8850 1150);
PAINT AQUA (-8850 1150);
FORCEPROP 2 LAST $XR0 85 
J 0
(-9071 1150);
DISPLAY 0.638298 (-9071 1150);
PAINT MONO (-9071 1150);
FORCEPROP 2 LAST CDS_LIB standard
J 0
(-8850 1150);
DISPLAY INVISIBLE (-8850 1150);
FORCEPROP 1 LAST OFFPAGE TRUE
J 0
(-8525 1025);
DISPLAY 0.872340 (-8525 1025);
PAINT AQUA (-8525 1025);
DISPLAY INVISIBLE (-8525 1025);
FORCEPROP 1 LAST COMMENT_BODY TRUE
J 0
(-8725 1050);
DISPLAY 0.872340 (-8725 1050);
PAINT GREEN (-8725 1050);
DISPLAY INVISIBLE (-8725 1050);
FORCEPROP 2 LAST PATH I36
J 0
(-9100 1200);
DISPLAY 0.680851 (-9100 1200);
DISPLAY INVISIBLE (-9100 1200);
FORCEADD OFFPAGE..1
(-8800 2800);
PAINT AQUA (-8800 2800);
FORCEPROP 2 LAST $XR1 81 
J 0
(-9141 2800);
DISPLAY 0.638298 (-9141 2800);
PAINT MONO (-9141 2800);
FORCEPROP 2 LAST $XR0 28 
J 0
(-9051 2800);
DISPLAY 0.638298 (-9051 2800);
PAINT MONO (-9051 2800);
FORCEPROP 2 LAST CDS_LIB standard
J 0
(-8800 2800);
DISPLAY INVISIBLE (-8800 2800);
FORCEPROP 1 LAST OFFPAGE TRUE
J 0
(-8475 2675);
DISPLAY 0.872340 (-8475 2675);
PAINT AQUA (-8475 2675);
DISPLAY INVISIBLE (-8475 2675);
FORCEPROP 1 LAST COMMENT_BODY TRUE
J 0
(-8675 2700);
DISPLAY 0.872340 (-8675 2700);
PAINT GREEN (-8675 2700);
DISPLAY INVISIBLE (-8675 2700);
FORCEPROP 2 LAST PATH I37
J 0
(-9050 2875);
DISPLAY 0.680851 (-9050 2875);
DISPLAY INVISIBLE (-9050 2875);
FORCEADD MOSFET_NCH_DUAL..1
(-7700 2850);
FORCEPROP 1 LAST LOCATION Q87
J 0
(-7549 2824);
DISPLAY 0.723404 (-7549 2824);
PAINT GREEN (-7549 2824);
FORCEPROP 0 LAST $SEC 1
J 0
(-7525 2975);
DISPLAY INVISIBLE (-7525 2975);
FORCEPROP 0 LAST CDS_SEC 1
J 0
(-7525 2975);
DISPLAY INVISIBLE (-7525 2975);
FORCEPROP 0 LASTPIN (-7650 3050) $PN 6
R 1
J 0
(-7660 3060);
DISPLAY 0.808511 (-7660 3060);
FORCEPROP 0 LASTPIN (-7900 2800) $PN 2
J 2
(-7910 2810);
DISPLAY 0.808511 (-7910 2810);
FORCEPROP 0 LASTPIN (-7650 2650) $PN 1
R 1
J 2
(-7660 2640);
DISPLAY 0.808511 (-7660 2640);
FORCEPROP 2 LAST PART_TYPE SMLF
J 0
(-7525 2925);
DISPLAY 1.021277 (-7525 2925);
FORCEPROP 1 LAST MATERIAL IC
J 0
(-7549 2699);
DISPLAY 0.723404 (-7549 2699);
PAINT GREEN (-7549 2699);
FORCEPROP 2 LAST VALUE PJT138K
J 0
(-7525 2875);
DISPLAY 1.021277 (-7525 2875);
FORCEPROP 1 LAST NEEDS_NO_SIZE TRUE
J 0
(-7700 2849);
DISPLAY 0.468085 (-7700 2849);
PAINT GREEN (-7700 2849);
DISPLAY INVISIBLE (-7700 2849);
FORCEPROP 1 LAST CDS_LMAN_SYM_OUTLINE -150,150,150,-150
J 0
(-7700 2850);
DISPLAY 0.468085 (-7700 2850);
PAINT GREEN (-7700 2850);
DISPLAY INVISIBLE (-7700 2850);
FORCEPROP 2 LAST CDS_LIB pure_quanta
J 0
(-7700 2850);
DISPLAY INVISIBLE (-7700 2850);
FORCEPROP 1 LAST PATH I38
J 0
(-7700 2850);
DISPLAY 0.723404 (-7700 2850);
PAINT GREEN (-7700 2850);
DISPLAY INVISIBLE (-7700 2850);
FORCEPROP 1 LAST PART_NUMBER BAM138K0003
J 0
(-7549 2764);
DISPLAY 0.723404 (-7549 2764);
PAINT GREEN (-7549 2764);
DISPLAY INVISIBLE (-7549 2764);
FORCEADD UNIVERSAL_GND..1
(-7650 2500);
FORCEPROP 3 LASTPIN (-7650 2550) SIG_NAME GND\g
J 0
(-7640 2560);
DISPLAY 0.659574 (-7640 2560);
PAINT MONO (-7640 2560);
DISPLAY INVISIBLE (-7640 2560);
FORCEPROP 2 LAST CDS_LIB pure_quanta_power
J 0
(-7650 2500);
DISPLAY INVISIBLE (-7650 2500);
FORCEPROP 1 LAST HDL_POWER GND
J 1
(-7625 2425);
DISPLAY 0.872340 (-7625 2425);
PAINT GREEN (-7625 2425);
DISPLAY INVISIBLE (-7625 2425);
FORCEPROP 1 LAST PATH I39
J 0
(-7575 2500);
DISPLAY 0.872340 (-7575 2500);
PAINT AQUA (-7575 2500);
DISPLAY INVISIBLE (-7575 2500);
FORCEADD UNIVERSAL_GND..1
(-2650 1950);
FORCEPROP 3 LASTPIN (-2650 2000) SIG_NAME GND\g
J 0
(-2640 2010);
DISPLAY 0.659574 (-2640 2010);
PAINT MONO (-2640 2010);
DISPLAY INVISIBLE (-2640 2010);
FORCEPROP 2 LAST CDS_LIB pure_quanta_power
J 0
(-2650 1950);
DISPLAY INVISIBLE (-2650 1950);
FORCEPROP 1 LAST HDL_POWER GND
J 1
(-2625 1875);
DISPLAY 0.872340 (-2625 1875);
PAINT GREEN (-2625 1875);
DISPLAY INVISIBLE (-2625 1875);
FORCEPROP 1 LAST PATH I4
J 0
(-2575 1950);
DISPLAY 0.872340 (-2575 1950);
PAINT AQUA (-2575 1950);
DISPLAY INVISIBLE (-2575 1950);
FORCEADD Q_LED..1
R 2
(-6625 3125);
FORCEPROP 1 LAST LOCATION D93
J 0
(-6725 3050);
DISPLAY 0.723404 (-6725 3050);
PAINT GREEN (-6725 3050);
FORCEPROP 0 LAST $SEC 1
J 0
(-6725 3100);
DISPLAY INVISIBLE (-6725 3100);
FORCEPROP 0 LAST CDS_SEC 1
J 0
(-6725 3100);
DISPLAY INVISIBLE (-6725 3100);
FORCEPROP 0 LASTPIN (-6475 3125) $PN A
J 0
(-6465 3135);
DISPLAY 0.808511 (-6465 3135);
FORCEPROP 0 LASTPIN (-6775 3125) $PN C
J 2
(-6785 3135);
DISPLAY 0.808511 (-6785 3135);
FORCEPROP 1 LAST MATERIAL IC
J 0
(-6600 2950);
DISPLAY 0.723404 (-6600 2950);
PAINT GREEN (-6600 2950);
FORCEPROP 2 LAST COLOR LED_BLUE
J 0
(-6725 3000);
DISPLAY 0.638298 (-6725 3000);
FORCEPROP 0 LAST PACK_TYPE SMLF
J 0
(-6725 2950);
DISPLAY 0.638298 (-6725 2950);
FORCEPROP 2 LAST MANUF_PN LTST-C281TBKT-5A
J 0
(-6725 2850);
DISPLAY 0.638298 (-6725 2850);
FORCEPROP 1 LAST NEEDS_NO_SIZE TRUE
J 2
(-6603 3147);
DISPLAY 0.468085 (-6603 3147);
PAINT GREEN (-6603 3147);
DISPLAY INVISIBLE (-6603 3147);
FORCEPROP 2 LAST CDS_LIB pure_quanta
J 0
(-6625 3125);
DISPLAY INVISIBLE (-6625 3125);
FORCEPROP 1 LAST PATH I40
J 2
(-6750 3205);
DISPLAY 0.723404 (-6750 3205);
PAINT GREEN (-6750 3205);
DISPLAY INVISIBLE (-6750 3205);
FORCEPROP 1 LAST PART_NUMBER BEBL0172Z00
J 0
(-6725 2900);
DISPLAY 0.574468 (-6725 2900);
PAINT GREEN (-6725 2900);
DISPLAY INVISIBLE (-6725 2900);
FORCEADD Q_RES..1
(-5200 3125);
FORCEPROP 1 LAST LOCATION R3074
J 0
(-5250 3175);
DISPLAY 0.978723 (-5250 3175);
FORCEPROP 0 LAST $SEC 1
J 0
(-5250 3225);
DISPLAY 0.680851 (-5250 3225);
PAINT MONO (-5250 3225);
DISPLAY INVISIBLE (-5250 3225);
FORCEPROP 0 LAST CDS_SEC 1
J 0
(-5250 3225);
DISPLAY 1.021277 (-5250 3225);
DISPLAY INVISIBLE (-5250 3225);
FORCEPROP 1 LASTPIN (-5300 3125) $PN 1
J 0
(-5288 3137);
DISPLAY 0.787234 (-5288 3137);
PAINT MONO (-5288 3137);
FORCEPROP 1 LASTPIN (-5100 3125) $PN 2
J 0
(-5138 3137);
DISPLAY 0.787234 (-5138 3137);
PAINT MONO (-5138 3137);
FORCEPROP 1 LAST PACK_TYPE 0402LF
J 0
(-4900 3125);
DISPLAY 0.638298 (-4900 3125);
FORCEPROP 1 LAST MATERIAL CHIP
J 0
(-5350 3075);
DISPLAY 0.638298 (-5350 3075);
FORCEPROP 1 LAST VALUE 130
J 2
(-5000 3125);
DISPLAY 0.638298 (-5000 3125);
FORCEPROP 1 LAST WATTAGE 1/16W
J 2
(-5050 3075);
DISPLAY 0.638298 (-5050 3075);
FORCEPROP 1 LAST TOLERANCE 1%
J 0
(-4975 3125);
DISPLAY 0.638298 (-4975 3125);
FORCEPROP 2 LAST CDS_LIB pure_quanta
J 0
(-5200 3125);
DISPLAY INVISIBLE (-5200 3125);
FORCEPROP 1 LAST PATH I41
J 0
(-5250 3275);
DISPLAY 0.978723 (-5250 3275);
PAINT WHITE (-5250 3275);
DISPLAY INVISIBLE (-5250 3275);
FORCEPROP 1 LAST PART_NUMBER CS11302FB03
J 0
(-5425 3225);
DISPLAY 0.638298 (-5425 3225);
DISPLAY INVISIBLE (-5425 3225);
FORCEADD UNIVERSAL_POWER..1
(-4600 3300);
FORCEPROP 3 LASTPIN (-4600 3250) SIG_NAME P3V3_AUX\g
J 0
(-4590 3260);
DISPLAY 0.659574 (-4590 3260);
PAINT MONO (-4590 3260);
DISPLAY INVISIBLE (-4590 3260);
FORCEPROP 1 LAST HDL_POWER P3V3_AUX
J 1
(-4600 3350);
DISPLAY 0.723404 (-4600 3350);
PAINT GREEN (-4600 3350);
FORCEPROP 2 LAST CDS_LIB pure_quanta_power
J 0
(-4600 3300);
DISPLAY INVISIBLE (-4600 3300);
FORCEPROP 1 LAST PATH I42
J 0
(-4550 3325);
DISPLAY 0.872340 (-4550 3325);
PAINT AQUA (-4550 3325);
DISPLAY INVISIBLE (-4550 3325);
FORCEADD Q_LED..1
R 2
(-1875 3950);
FORCEPROP 1 LAST LOCATION D6000
J 0
(-1975 3875);
DISPLAY 0.723404 (-1975 3875);
PAINT GREEN (-1975 3875);
FORCEPROP 0 LAST $SEC 1
J 0
(-1975 3925);
DISPLAY INVISIBLE (-1975 3925);
FORCEPROP 0 LAST CDS_SEC 1
J 0
(-1975 3925);
DISPLAY INVISIBLE (-1975 3925);
FORCEPROP 0 LASTPIN (-1725 3950) $PN A
J 0
(-1715 3960);
DISPLAY 0.808511 (-1715 3960);
FORCEPROP 0 LASTPIN (-2025 3950) $PN C
J 2
(-2035 3960);
DISPLAY 0.808511 (-2035 3960);
FORCEPROP 0 LAST PACK_TYPE SMLF
J 0
(-1975 3775);
DISPLAY 0.638298 (-1975 3775);
FORCEPROP 1 LAST MATERIAL IC
J 0
(-1850 3775);
DISPLAY 0.723404 (-1850 3775);
PAINT GREEN (-1850 3775);
FORCEPROP 2 LAST MANUF_PN LTST-C281TBKT-5A
J 0
(-1975 3675);
DISPLAY 0.638298 (-1975 3675);
FORCEPROP 2 LAST COLOR LED_BLUE
J 0
(-1975 3825);
DISPLAY 0.638298 (-1975 3825);
FORCEPROP 1 LAST NEEDS_NO_SIZE TRUE
J 2
(-1853 3972);
DISPLAY 0.468085 (-1853 3972);
PAINT GREEN (-1853 3972);
DISPLAY INVISIBLE (-1853 3972);
FORCEPROP 2 LAST CDS_LIB pure_quanta
J 0
(-1875 3950);
DISPLAY INVISIBLE (-1875 3950);
FORCEPROP 1 LAST PATH I43
J 2
(-2000 4030);
DISPLAY 0.723404 (-2000 4030);
PAINT GREEN (-2000 4030);
DISPLAY INVISIBLE (-2000 4030);
FORCEPROP 1 LAST PART_NUMBER BEBL0172Z00
J 0
(-1975 3725);
DISPLAY 0.574468 (-1975 3725);
PAINT GREEN (-1975 3725);
DISPLAY INVISIBLE (-1975 3725);
FORCEADD UNIVERSAL_POWER..1
(-250 4075);
FORCEPROP 3 LASTPIN (-250 4025) SIG_NAME P3V3_AUX\g
J 0
(-240 4035);
DISPLAY 0.659574 (-240 4035);
PAINT MONO (-240 4035);
DISPLAY INVISIBLE (-240 4035);
FORCEPROP 1 LAST HDL_POWER P3V3_AUX
J 1
(-250 4125);
DISPLAY 0.723404 (-250 4125);
PAINT GREEN (-250 4125);
FORCEPROP 2 LAST CDS_LIB pure_quanta_power
J 0
(-250 4075);
DISPLAY INVISIBLE (-250 4075);
FORCEPROP 1 LAST PATH I44
J 0
(-200 4100);
DISPLAY 0.872340 (-200 4100);
PAINT AQUA (-200 4100);
DISPLAY INVISIBLE (-200 4100);
FORCEADD Q_RES..1
(-775 3950);
FORCEPROP 1 LAST LOCATION R6246
J 0
(-825 4000);
DISPLAY 0.978723 (-825 4000);
FORCEPROP 0 LAST $SEC 1
J 0
(-825 4050);
DISPLAY 0.680851 (-825 4050);
PAINT MONO (-825 4050);
DISPLAY INVISIBLE (-825 4050);
FORCEPROP 0 LAST CDS_SEC 1
J 0
(-825 4050);
DISPLAY 1.021277 (-825 4050);
DISPLAY INVISIBLE (-825 4050);
FORCEPROP 1 LASTPIN (-875 3950) $PN 1
J 0
(-863 3962);
DISPLAY 0.787234 (-863 3962);
PAINT MONO (-863 3962);
FORCEPROP 1 LASTPIN (-675 3950) $PN 2
J 0
(-713 3962);
DISPLAY 0.787234 (-713 3962);
PAINT MONO (-713 3962);
FORCEPROP 1 LAST PACK_TYPE 0402LF
J 0
(-475 3950);
DISPLAY 0.638298 (-475 3950);
FORCEPROP 1 LAST TOLERANCE 1%
J 0
(-550 3950);
DISPLAY 0.638298 (-550 3950);
FORCEPROP 1 LAST VALUE 130
J 2
(-575 3950);
DISPLAY 0.638298 (-575 3950);
FORCEPROP 1 LAST MATERIAL CHIP
J 0
(-925 3900);
DISPLAY 0.638298 (-925 3900);
FORCEPROP 1 LAST WATTAGE 1/16W
J 2
(-625 3900);
DISPLAY 0.638298 (-625 3900);
FORCEPROP 2 LAST CDS_LIB pure_quanta
J 0
(-775 3950);
DISPLAY INVISIBLE (-775 3950);
FORCEPROP 1 LAST PATH I45
J 0
(-825 4100);
DISPLAY 0.978723 (-825 4100);
PAINT WHITE (-825 4100);
DISPLAY INVISIBLE (-825 4100);
FORCEPROP 1 LAST PART_NUMBER CS11302FB03
J 0
(-1000 4050);
DISPLAY 0.638298 (-1000 4050);
DISPLAY INVISIBLE (-1000 4050);
FORCEADD UNIVERSAL_GND..1
(-2825 3325);
FORCEPROP 3 LASTPIN (-2825 3375) SIG_NAME GND\g
J 0
(-2815 3385);
DISPLAY 0.659574 (-2815 3385);
PAINT MONO (-2815 3385);
DISPLAY INVISIBLE (-2815 3385);
FORCEPROP 2 LAST CDS_LIB pure_quanta_power
J 0
(-2825 3325);
DISPLAY INVISIBLE (-2825 3325);
FORCEPROP 1 LAST HDL_POWER GND
J 1
(-2800 3250);
DISPLAY 0.872340 (-2800 3250);
PAINT GREEN (-2800 3250);
DISPLAY INVISIBLE (-2800 3250);
FORCEPROP 1 LAST PATH I46
J 0
(-2750 3325);
DISPLAY 0.872340 (-2750 3325);
PAINT AQUA (-2750 3325);
DISPLAY INVISIBLE (-2750 3325);
FORCEADD MOSFET_NCH_DUAL..1
(-2875 3675);
FORCEPROP 1 LAST LOCATION Q6000
J 0
(-2724 3649);
DISPLAY 0.723404 (-2724 3649);
PAINT GREEN (-2724 3649);
FORCEPROP 0 LAST $SEC 1
J 0
(-2700 3800);
DISPLAY INVISIBLE (-2700 3800);
FORCEPROP 0 LAST CDS_SEC 1
J 0
(-2700 3800);
DISPLAY INVISIBLE (-2700 3800);
FORCEPROP 0 LASTPIN (-2825 3875) $PN 6
R 1
J 0
(-2835 3885);
DISPLAY 0.808511 (-2835 3885);
FORCEPROP 0 LASTPIN (-3075 3625) $PN 2
J 2
(-3085 3635);
DISPLAY 0.808511 (-3085 3635);
FORCEPROP 0 LASTPIN (-2825 3475) $PN 1
R 1
J 2
(-2835 3465);
DISPLAY 0.808511 (-2835 3465);
FORCEPROP 1 LAST MATERIAL IC
J 0
(-2724 3524);
DISPLAY 0.723404 (-2724 3524);
PAINT GREEN (-2724 3524);
FORCEPROP 2 LAST VALUE PJT138K
J 0
(-2700 3700);
DISPLAY 1.021277 (-2700 3700);
FORCEPROP 2 LAST PART_TYPE SMLF
J 0
(-2700 3750);
DISPLAY 1.021277 (-2700 3750);
FORCEPROP 1 LAST NEEDS_NO_SIZE TRUE
J 0
(-2875 3674);
DISPLAY 0.468085 (-2875 3674);
PAINT GREEN (-2875 3674);
DISPLAY INVISIBLE (-2875 3674);
FORCEPROP 1 LAST CDS_LMAN_SYM_OUTLINE -150,150,150,-150
J 0
(-2875 3675);
DISPLAY 0.468085 (-2875 3675);
PAINT GREEN (-2875 3675);
DISPLAY INVISIBLE (-2875 3675);
FORCEPROP 2 LAST CDS_LIB pure_quanta
J 0
(-2875 3675);
DISPLAY INVISIBLE (-2875 3675);
FORCEPROP 1 LAST PATH I47
J 0
(-2875 3675);
DISPLAY 0.723404 (-2875 3675);
PAINT GREEN (-2875 3675);
DISPLAY INVISIBLE (-2875 3675);
FORCEPROP 1 LAST PART_NUMBER BAM138K0003
J 0
(-2724 3589);
DISPLAY 0.723404 (-2724 3589);
PAINT GREEN (-2724 3589);
DISPLAY INVISIBLE (-2724 3589);
FORCEADD OFFPAGE..1
(-3850 3625);
PAINT AQUA (-3850 3625);
FORCEPROP 2 LAST $XR1 81 
J 0
(-4192 3625);
DISPLAY 0.638298 (-4192 3625);
PAINT MONO (-4192 3625);
FORCEPROP 2 LAST $XR0 271 
J 0
(-4102 3625);
DISPLAY 0.638298 (-4102 3625);
PAINT MONO (-4102 3625);
FORCEPROP 2 LAST CDS_LIB standard
J 0
(-3850 3625);
DISPLAY INVISIBLE (-3850 3625);
FORCEPROP 1 LAST OFFPAGE TRUE
J 0
(-3525 3500);
DISPLAY 0.872340 (-3525 3500);
PAINT AQUA (-3525 3500);
DISPLAY INVISIBLE (-3525 3500);
FORCEPROP 1 LAST COMMENT_BODY TRUE
J 0
(-3725 3525);
DISPLAY 0.872340 (-3725 3525);
PAINT GREEN (-3725 3525);
DISPLAY INVISIBLE (-3725 3525);
FORCEPROP 2 LAST PATH I48
J 0
(-4100 3675);
DISPLAY 0.680851 (-4100 3675);
DISPLAY INVISIBLE (-4100 3675);
FORCEADD UNIVERSAL_GND..1
(-7700 5300);
FORCEPROP 3 LASTPIN (-7700 5350) SIG_NAME GND\g
J 0
(-7690 5360);
DISPLAY 0.659574 (-7690 5360);
PAINT MONO (-7690 5360);
DISPLAY INVISIBLE (-7690 5360);
FORCEPROP 2 LAST CDS_LIB pure_quanta_power
J 0
(-7700 5300);
DISPLAY INVISIBLE (-7700 5300);
FORCEPROP 1 LAST HDL_POWER GND
J 1
(-7675 5225);
DISPLAY 0.872340 (-7675 5225);
PAINT GREEN (-7675 5225);
DISPLAY INVISIBLE (-7675 5225);
FORCEPROP 1 LAST PATH I5
J 0
(-7625 5300);
DISPLAY 0.872340 (-7625 5300);
PAINT AQUA (-7625 5300);
DISPLAY INVISIBLE (-7625 5300);
FORCEADD Q_RES..1
(-1025 975);
FORCEPROP 1 LAST LOCATION R3100
J 0
(-1075 1025);
DISPLAY 0.978723 (-1075 1025);
FORCEPROP 0 LAST $SEC 1
J 0
(-1075 1075);
DISPLAY 0.680851 (-1075 1075);
PAINT MONO (-1075 1075);
DISPLAY INVISIBLE (-1075 1075);
FORCEPROP 0 LAST CDS_SEC 1
J 0
(-1075 1075);
DISPLAY 1.021277 (-1075 1075);
DISPLAY INVISIBLE (-1075 1075);
FORCEPROP 1 LASTPIN (-1125 975) $PN 1
J 0
(-1113 987);
DISPLAY 0.787234 (-1113 987);
PAINT MONO (-1113 987);
FORCEPROP 1 LASTPIN (-925 975) $PN 2
J 0
(-963 987);
DISPLAY 0.787234 (-963 987);
PAINT MONO (-963 987);
FORCEPROP 1 LAST PACK_TYPE 0402LF
J 0
(-725 975);
DISPLAY 0.638298 (-725 975);
FORCEPROP 1 LAST MATERIAL CHIP
J 0
(-1175 925);
DISPLAY 0.638298 (-1175 925);
FORCEPROP 1 LAST TOLERANCE 1%
J 0
(-800 975);
DISPLAY 0.638298 (-800 975);
FORCEPROP 1 LAST VALUE 130
J 2
(-825 975);
DISPLAY 0.638298 (-825 975);
FORCEPROP 1 LAST WATTAGE 1/16W
J 2
(-875 925);
DISPLAY 0.638298 (-875 925);
FORCEPROP 2 LAST CDS_LIB pure_quanta
J 0
(-1025 975);
DISPLAY INVISIBLE (-1025 975);
FORCEPROP 1 LAST PATH I8
J 0
(-1075 1125);
DISPLAY 0.978723 (-1075 1125);
PAINT WHITE (-1075 1125);
DISPLAY INVISIBLE (-1075 1125);
FORCEPROP 1 LAST PART_NUMBER CS11302FB03
J 0
(-1250 1075);
DISPLAY 0.638298 (-1250 1075);
DISPLAY INVISIBLE (-1250 1075);
FORCEADD Q_RES..1
(-950 2200);
FORCEPROP 1 LAST LOCATION R3102
J 0
(-1075 2200);
DISPLAY 0.638298 (-1075 2200);
FORCEPROP 0 LAST $SEC 1
J 0
(-1075 2250);
DISPLAY 0.680851 (-1075 2250);
PAINT MONO (-1075 2250);
DISPLAY INVISIBLE (-1075 2250);
FORCEPROP 0 LAST CDS_SEC 1
J 0
(-1075 2250);
DISPLAY 1.021277 (-1075 2250);
DISPLAY INVISIBLE (-1075 2250);
FORCEPROP 1 LASTPIN (-1050 2200) $PN 1
J 0
(-1038 2212);
DISPLAY 0.787234 (-1038 2212);
PAINT MONO (-1038 2212);
FORCEPROP 1 LASTPIN (-850 2200) $PN 2
J 0
(-888 2212);
DISPLAY 0.787234 (-888 2212);
PAINT MONO (-888 2212);
FORCEPROP 1 LAST VALUE 470
J 2
(-1000 2150);
DISPLAY 0.638298 (-1000 2150);
FORCEPROP 1 LAST MATERIAL CHIP
J 0
(-1075 2075);
DISPLAY 0.638298 (-1075 2075);
FORCEPROP 1 LAST WATTAGE 1/16W
J 2
(-800 2075);
DISPLAY 0.638298 (-800 2075);
FORCEPROP 1 LAST PACK_TYPE 0402LF
J 0
(-900 2150);
DISPLAY 0.638298 (-900 2150);
FORCEPROP 1 LAST TOLERANCE 1%
J 0
(-975 2150);
DISPLAY 0.638298 (-975 2150);
FORCEPROP 2 LAST CDS_LIB pure_quanta
J 0
(-950 2200);
DISPLAY INVISIBLE (-950 2200);
FORCEPROP 1 LAST PATH I9
J 0
(-1000 2350);
DISPLAY 0.978723 (-1000 2350);
PAINT WHITE (-1000 2350);
DISPLAY INVISIBLE (-1000 2350);
FORCEPROP 1 LAST PART_NUMBER CS14702FB04
J 0
(-1075 2125);
DISPLAY 0.638298 (-1075 2125);
DISPLAY INVISIBLE (-1075 2125);
FORCEADD QUANTA_TITLE_BLOCK_C..1
(0 0);
FORCEPROP 0 LAST CDS_CON_LAST_MODIFIED Thu Sep 14 16:12:37 2023
J 0
(-1885 15);
DISPLAY INVISIBLE (-1885 15);
FORCEPROP 1 LAST CUSTOM_TXT_CDS <CON_LAST_MODIFIED>
J 0
(-1885 15);
DISPLAY 0.978723 (-1885 15);
FORCEPROP 2 LAST CUSTOM_TXT_CDS <XR_PAGE_TITLE>
J 0
(-7890 5250);
DISPLAY 0.638298 (-7890 5250);
PAINT PINK (-7890 5250);
DISPLAY INVISIBLE (-7890 5250);
FORCEPROP 1 LAST CUSTOM_TXT_CDS <NAME_2>
J 0
(-3175 50);
FORCEPROP 1 LAST CUSTOM_TXT_CDS <NAME_1>
J 0
(-3175 175);
FORCEPROP 1 LAST CUSTOM_TXT_CDS <Q_NUMBER>
J 0
(-1403 103);
DISPLAY 1.212766 (-1403 103);
FORCEPROP 1 LAST CUSTOM_TXT_CDS <Q_PROJ>
J 0
(-2382 102);
DISPLAY 1.212766 (-2382 102);
FORCEPROP 1 LAST CUSTOM_TXT_CDS <Q_REV>
J 0
(-184 103);
DISPLAY 1.212766 (-184 103);
FORCEPROP 1 LAST CUSTOM_TXT_CDS <CON_PAGE_NUM> OF <CON_TOTAL_PAGES>
J 0
(-446 18);
DISPLAY 0.978723 (-446 18);
FORCEPROP 1 LAST Q_TITLE POWER GOOD LED'S 1/3
J 0
(-9366 26);
DISPLAY 2.446809 (-9366 26);
PAINT GREEN (-9366 26);
FORCEPROP 2 LAST CDS_LIB pure_quanta
J 0
(0 0);
DISPLAY INVISIBLE (0 0);
FORCEPROP 1 LAST CDS_LMAN_SYM_OUTLINE -9475,6775,100,-125
J 0
(0 0);
DISPLAY 0.468085 (0 0);
PAINT GREEN (0 0);
DISPLAY INVISIBLE (0 0);
FORCEPROP 2 LAST PAGE_BORDER TRUE
J 0
(-7890 5250);
DISPLAY 0.638298 (-7890 5250);
PAINT PINK (-7890 5250);
DISPLAY INVISIBLE (-7890 5250);
FORCEPROP 2 LAST CDS_XR_PAGE_TITLE CR-255 : @T6G_MB_LIB.T6G(SCH_1):PAGE255
J 0
(-7890 5250);
DISPLAY 0.638298 (-7890 5250);
PAINT PINK (-7890 5250);
DISPLAY INVISIBLE (-7890 5250);
FORCEPROP 1 LAST Q_DEPT BU9
J 1
(-3763 49);
DISPLAY 1.957447 (-3763 49);
PAINT GREEN (-3763 49);
DISPLAY INVISIBLE (-3763 49);
FORCEPROP 1 LAST COMMENT_BODY TRUE
J 0
(12 -13);
DISPLAY 0.978723 (12 -13);
PAINT GREEN (12 -13);
DISPLAY INVISIBLE (12 -13);
WIRE 16 -1 (-4725 5925)(-4725 6025);
WIRE 16 -1 (-4725 5925)(-5275 5925);
WIRE 16 -1 (-2275 975)(-2725 975);
WIRE 16 -1 (-2725 975)(-2725 775);
WIRE 16 -1 (-7625 3975)(-7625 4075);
WIRE 16 -1 (-4600 4550)(-4600 4650);
WIRE 16 -1 (-4600 4550)(-5150 4550);
WIRE 16 -1 (-4725 1475)(-4725 1625);
WIRE 16 -1 (-4725 1475)(-5275 1475);
WIRE 16 -1 (-7700 900)(-7700 1000);
WIRE 16 -1 (-7650 2550)(-7650 2650);
WIRE 16 -1 (-2200 2200)(-2650 2200);
WIRE 16 -1 (-2650 2200)(-2650 2000);
WIRE 16 -1 (-4600 3125)(-4600 3250);
WIRE 16 -1 (-4600 3125)(-5100 3125);
WIRE 16 -1 (-250 3950)(-250 4025);
WIRE 16 -1 (-250 3950)(-675 3950);
WIRE 16 -1 (-2825 3375)(-2825 3475);
WIRE 16 -1 (-7700 5350)(-7700 5450);
WIRE 74 -1 (-875 2650)(-875 2850);
WIRE 74 -1 (-3025 2650)(-875 2650);
WIRE 74 -1 (-875 2850)(-3025 2850);
WIRE 74 -1 (-3025 2850)(-3025 2650);
WIRE 16 -1 (-850 2200)(-550 2200);
WIRE 16 -1 (-550 2400)(-550 2200);
WIRE 16 -1 (-925 975)(-500 975);
WIRE 16 -1 (-500 1150)(-500 975);
WIRE 74 -1 (-875 4225)(-875 4425);
WIRE 74 -1 (-3125 4225)(-875 4225);
WIRE 74 -1 (-875 4425)(-3125 4425);
WIRE 74 -1 (-3125 4425)(-3125 4225);
WIRE 16 -1 (-2825 3950)(-2025 3950);
WIRE 16 -1 (-2825 3875)(-2825 3950);
FORCEPROP 2 LAST SIG_NAME LED_PWRGD_P1V2_AUX_D
J 0
(-2835 3960);
DISPLAY 0.723404 (-2835 3960);
FORCEPROP 2 LASTPROP $XRERR UNIQUE?
J 0
(-3075 3960);
DISPLAY 0.638298 (-3075 3960);
PAINT MONO (-3075 3960);
DISPLAY INVISIBLE (-3075 3960);
WIRE 16 -1 (-3075 3625)(-3800 3625);
FORCEPROP 2 LAST SIG_NAME PWRGD_P1V2_AUX_R
J 0
(-3660 3635);
DISPLAY 0.617021 (-3660 3635);
WIRE 16 -1 (-1725 3950)(-875 3950);
FORCEPROP 0 LAST SIG_NAME LED_PWRGD_P1V2_AUX
J 0
(-1585 3975);
DISPLAY 0.723404 (-1585 3975);
FORCEPROP 2 LASTPROP $XRERR UNIQUE?
J 0
(-1825 3975);
DISPLAY 0.638298 (-1825 3975);
PAINT MONO (-1825 3975);
DISPLAY INVISIBLE (-1825 3975);
WIRE 16 -1 (-6450 4550)(-5350 4550);
FORCEPROP 2 LAST SIG_NAME LED_PWRGD_P1V8_AUX
J 0
(-6285 4560);
DISPLAY 0.723404 (-6285 4560);
FORCEPROP 2 LASTPROP $XRERR UNIQUE?
J 0
(-6525 4560);
DISPLAY 0.638298 (-6525 4560);
PAINT MONO (-6525 4560);
DISPLAY INVISIBLE (-6525 4560);
WIRE 74 -1 (-6450 4875)(-6450 5075);
WIRE 74 -1 (-8700 4875)(-6450 4875);
WIRE 74 -1 (-6450 5075)(-8700 5075);
WIRE 74 -1 (-8700 5075)(-8700 4875);
WIRE 16 -1 (-7625 4550)(-6750 4550);
WIRE 16 -1 (-7625 4475)(-7625 4550);
FORCEPROP 2 LAST SIG_NAME LED_PWRGD_P1V8_AUX_D
J 0
(-7635 4560);
DISPLAY 0.723404 (-7635 4560);
FORCEPROP 2 LASTPROP $XRERR UNIQUE?
J 0
(-7875 4560);
DISPLAY 0.638298 (-7875 4560);
PAINT MONO (-7875 4560);
DISPLAY INVISIBLE (-7875 4560);
WIRE 16 -1 (-7875 4225)(-8725 4225);
FORCEPROP 2 LAST SIG_NAME PWRGD_P1V8_AUX_R
J 0
(-8585 4235);
DISPLAY 0.617021 (-8585 4235);
WIRE 74 -1 (-6325 3450)(-6325 3650);
WIRE 74 -1 (-8725 3450)(-6325 3450);
WIRE 74 -1 (-6325 3650)(-8725 3650);
WIRE 74 -1 (-8725 3650)(-8725 3450);
WIRE 16 -1 (-6525 1475)(-5475 1475);
FORCEPROP 2 LAST SIG_NAME LED_PWRGD_SYS_PWROK_R
J 0
(-6360 1485);
DISPLAY 0.723404 (-6360 1485);
FORCEPROP 2 LASTPROP $XRERR UNIQUE?
J 0
(-6600 1485);
DISPLAY 0.638298 (-6600 1485);
PAINT MONO (-6600 1485);
DISPLAY INVISIBLE (-6600 1485);
WIRE 16 -1 (-6525 5925)(-5475 5925);
FORCEPROP 2 LAST SIG_NAME LED_PWRGD_PS_PWROK_PLD
J 0
(-6460 5950);
DISPLAY 0.723404 (-6460 5950);
FORCEPROP 2 LASTPROP $XRERR UNIQUE?
J 0
(-6700 5950);
DISPLAY 0.638298 (-6700 5950);
PAINT MONO (-6700 5950);
DISPLAY INVISIBLE (-6700 5950);
WIRE 74 -1 (-6575 1700)(-6575 1900);
WIRE 74 -1 (-8725 1700)(-6575 1700);
WIRE 74 -1 (-6575 1900)(-8725 1900);
WIRE 74 -1 (-8725 1900)(-8725 1700);
WIRE 16 -1 (-6475 3125)(-5300 3125);
FORCEPROP 2 LAST SIG_NAME LED_RST_RSMRST_PLD_R_N
J 0
(-6310 3135);
DISPLAY 0.723404 (-6310 3135);
FORCEPROP 2 LASTPROP $XRERR UNIQUE?
J 0
(-6550 3135);
DISPLAY 0.638298 (-6550 3135);
PAINT MONO (-6550 3135);
DISPLAY INVISIBLE (-6550 3135);
WIRE 16 -1 (-7950 5600)(-8800 5600);
FORCEPROP 2 LAST SIG_NAME PWRGD_PS_PWROK_PLD
J 0
(-8735 5610);
DISPLAY 0.723404 (-8735 5610);
WIRE 74 -1 (-850 1475)(-850 1675);
WIRE 74 -1 (-3000 1475)(-850 1475);
WIRE 74 -1 (-850 1675)(-3000 1675);
WIRE 74 -1 (-3000 1675)(-3000 1475);
WIRE 16 -1 (-7900 2800)(-8750 2800);
FORCEPROP 2 LAST SIG_NAME RST_CPU0_RSMRST_N
J 0
(-8710 2810);
DISPLAY 0.723404 (-8710 2810);
WIRE 16 -1 (-7950 1150)(-8800 1150);
FORCEPROP 2 LAST SIG_NAME SCM_SYS_PWROK_R2
J 0
(-8610 1160);
DISPLAY 0.723404 (-8610 1160);
WIRE 74 -1 (-6450 6250)(-6450 6450);
WIRE 74 -1 (-8775 6250)(-6450 6250);
WIRE 74 -1 (-6450 6450)(-8775 6450);
WIRE 74 -1 (-8775 6450)(-8775 6250);
WIRE 16 -1 (-7650 3050)(-7650 3125);
WIRE 16 -1 (-7650 3125)(-6775 3125);
FORCEPROP 2 LAST SIG_NAME LED_RST_RSMRST_PLD_R_N_D
J 0
(-7635 3135);
DISPLAY 0.723404 (-7635 3135);
FORCEPROP 2 LASTPROP $XRERR UNIQUE?
J 0
(-7875 3135);
DISPLAY 0.638298 (-7875 3135);
PAINT MONO (-7875 3135);
DISPLAY INVISIBLE (-7875 3135);
WIRE 16 -1 (-7700 1475)(-6825 1475);
FORCEPROP 2 LAST SIG_NAME LED_PWRGD_SYS_PWROK_R_D
J 0
(-7685 1475);
DISPLAY 0.723404 (-7685 1475);
FORCEPROP 2 LASTPROP $XRERR UNIQUE?
J 0
(-7925 1475);
DISPLAY 0.638298 (-7925 1475);
PAINT MONO (-7925 1475);
DISPLAY INVISIBLE (-7925 1475);
WIRE 16 -1 (-7700 1400)(-7700 1475);
WIRE 16 -1 (-7700 5925)(-6825 5925);
WIRE 16 -1 (-7700 5850)(-7700 5925);
FORCEPROP 2 LAST SIG_NAME LED_PWRGD_PS_PWROK_PLD_D
J 0
(-7785 5950);
DISPLAY 0.723404 (-7785 5950);
FORCEPROP 2 LASTPROP $XRERR UNIQUE?
J 0
(-8025 5950);
DISPLAY 0.638298 (-8025 5950);
PAINT MONO (-8025 5950);
DISPLAY INVISIBLE (-8025 5950);
WIRE 16 -1 (-1125 975)(-1975 975);
FORCEPROP 2 LAST SIG_NAME LED_P3V3
J 0
(-1785 985);
DISPLAY 0.723404 (-1785 985);
FORCEPROP 2 LASTPROP $XRERR UNIQUE?
J 0
(-2025 985);
DISPLAY 0.638298 (-2025 985);
PAINT MONO (-2025 985);
DISPLAY INVISIBLE (-2025 985);
WIRE 16 -1 (-1050 2200)(-1900 2200);
FORCEPROP 2 LAST SIG_NAME LED_P5V
J 0
(-1710 2210);
DISPLAY 0.723404 (-1710 2210);
FORCEPROP 2 LASTPROP $XRERR UNIQUE?
J 0
(-1950 2210);
DISPLAY 0.638298 (-1950 2210);
PAINT MONO (-1950 2210);
DISPLAY INVISIBLE (-1950 2210);
FORCENOTE
PWRGD_P1V8_AUX          1 = ON
(-8575 4950) 0;
DISPLAY LEFT (-8575 4950);
DISPLAY 1.276596 (-8575 4950);
PAINT WHITE (-8575 4950);
FORCENOTE
P5V          1 = ON
(-2900 2725) 0;
DISPLAY LEFT (-2900 2725);
DISPLAY 1.276596 (-2900 2725);
PAINT WHITE (-2900 2725);
FORCENOTE
P3V3          1 = ON
(-2875 1550) 0;
DISPLAY LEFT (-2875 1550);
DISPLAY 1.276596 (-2875 1550);
PAINT WHITE (-2875 1550);
FORCENOTE
PWRGD_SYS_PWROK          1 = ON
(-8600 1775) 0;
DISPLAY LEFT (-8600 1775);
DISPLAY 1.276596 (-8600 1775);
PAINT WHITE (-8600 1775);
FORCENOTE
PWRGD_PS_PWROK          1 = ON
(-8650 6325) 0;
DISPLAY LEFT (-8650 6325);
DISPLAY 1.276596 (-8650 6325);
PAINT WHITE (-8650 6325);
FORCENOTE
RST_CPU0_RSMRST_N          1 = ON
(-8600 3525) 0;
DISPLAY LEFT (-8600 3525);
DISPLAY 1.276596 (-8600 3525);
PAINT WHITE (-8600 3525);
FORCENOTE
PWRGD_P1V2_AUX          1 = ON
(-3000 4300) 0;
DISPLAY LEFT (-3000 4300);
DISPLAY 1.276596 (-3000 4300);
PAINT WHITE (-3000 4300);
QUIT
